# BASEBOARD_FAB2 (Tioga Pass) — schematic netlist excerpt (pin names and nets, part order shuffled) for the footprints in the layout excerpt that follows; sources: Cadence DE-HDL packaged netlist, KiCad conversion of Wiwynn_Tioga_Pass_MB.brd

C1R2  CAP  0.22UF 16V 10% X7R  pkg 0402  page 106 : A = P3E_CPU0_PE3_OCP_TXP<0> ; B = P3E_OCP_CPU0_PE3_C_TXP<0>
C4U1  CAP  10UF 4V 20% X6S  pkg 0603LF  page 231 : A = PVPP_ABC ; B = GND
C25W25  CAP  1.0UF 16V 10% X6S  pkg 0402  page 149 : A = P1V15_AUX_BMC ; B = GND

(kicad_pcb
	(version 20260206)
	(generator "pcbnew")
	(generator_version "10.0")
	(general
		(thickness 1.6)
		(legacy_teardrops no)
	)
	(paper "A4")
	(title_block
		(title "Wiwynn_Tioga_Pass_MB.brd")
		(comment 1 "Tioga Pass / footprints 2537-2539 of 4770")
	)
	(layers
		(0 "F.Cu" signal "TOP")
		(4 "In1.Cu" signal "L2GND")
		(6 "In2.Cu" signal "L3")
		(8 "In3.Cu" signal "L4GND")
		(10 "In4.Cu" signal "L5")
		(12 "In5.Cu" signal "L6GND")
		(14 "In6.Cu" signal "L7VCC")
		(16 "In7.Cu" signal "L8VCC")
		(18 "In8.Cu" signal "L9GND")
		(20 "In9.Cu" signal "L10")
		(22 "In10.Cu" signal "L11GND")
		(24 "In11.Cu" signal "L12")
		(26 "In12.Cu" signal "L13GND")
		(2 "B.Cu" signal "BOTTOM")
		(9 "F.Adhes" user "F.Adhesive")
		(11 "B.Adhes" user "B.Adhesive")
		(13 "F.Paste" user "Package Geometry/Pastemask Top")
		(15 "B.Paste" user "Package Geometry/Pastemask Bottom")
		(5 "F.SilkS" user "Ref Des/Silkscreen Top")
		(7 "B.SilkS" user "Ref Des/Silkscreen Bottom")
		(1 "F.Mask" user "Board Geometry/Soldermask Top")
		(3 "B.Mask" user "Board Geometry/Soldermask Bottom")
		(17 "Dwgs.User" user "User.Drawings")
		(19 "Cmts.User" user "User.Comments")
		(21 "Eco1.User" user "User.Eco1")
		(23 "Eco2.User" user "User.Eco2")
		(25 "Edge.Cuts" user "Board Geometry/Outline")
		(27 "Margin" user)
		(31 "F.CrtYd" user "Package Geometry/Place Bound Top")
		(29 "B.CrtYd" user "Package Geometry/Place Bound Bottom")
		(35 "F.Fab" user "Ref Des/Assembly Top")
		(33 "B.Fab" user "Ref Des/Assembly Bottom")
	)
	(footprint ""
		(layer "B.Cu")
		(at 462.8134 -52.432458)
		(property "Reference" "C1R2"
			(at 0 0 0)
			(layer "B.SilkS")
			(hide yes)
			(effects
				(font
					(size 1.27 1.27)
				)
				(justify mirror)
			)
		)
		(property "Value" ""
			(at 0 0 0)
			(layer "B.Fab")
			(effects
				(font
					(size 1.27 1.27)
				)
				(justify mirror)
			)
		)
		(duplicate_pad_numbers_are_jumpers no)
		(fp_poly
			(pts
				(xy -0.3048 -0.1016) (xy -0.3048 0.9906) (xy 0.3048 0.9906) (xy 0.3048 -0.1016)
			)
			(stroke
				(width 0)
				(type default)
			)
			(fill no)
			(layer "B.CrtYd")
		)
		(fp_line
			(start -0.3048 -0.1016)
			(end 0.3048 -0.1016)
			(stroke
				(width 0.1)
				(type default)
			)
			(layer "B.Fab")
		)
		(fp_line
			(start -0.3048 0.9906)
			(end -0.3048 -0.1016)
			(stroke
				(width 0.1)
				(type default)
			)
			(layer "B.Fab")
		)
		(fp_line
			(start 0.3048 -0.1016)
			(end 0.3048 0.9906)
			(stroke
				(width 0.1)
				(type default)
			)
			(layer "B.Fab")
		)
		(fp_line
			(start 0.3048 0.9906)
			(end -0.3048 0.9906)
			(stroke
				(width 0.1)
				(type default)
			)
			(layer "B.Fab")
		)
		(pad "1" smd rect
			(at 0 0 180)
			(size 0.508 0.508)
			(layers "B.Cu" "B.Mask" "B.Paste")
			(net "P3E_CPU0_PE3_OCP_TXP<0>")
		)
		(pad "2" smd rect
			(at 0 0.889 180)
			(size 0.508 0.508)
			(layers "B.Cu" "B.Mask" "B.Paste")
			(net "P3E_OCP_CPU0_PE3_C_TXP<0>")
		)
		(zone
			(layer "B.Cu")
			(hatch none 0.5)
			(connect_pads
				(clearance 0)
			)
			(min_thickness 0.25)
			(keepout
				(tracks allowed)
				(vias not_allowed)
				(pads allowed)
				(copperpour not_allowed)
				(footprints allowed)
			)
			(placement
				(enabled no)
				(sheetname "")
			)
			(fill
				(thermal_gap 0.5)
				(thermal_bridge_width 0.5)
				(island_removal_mode 0)
			)
			(polygon
				(pts
					(xy 463.0674 -52.178458) (xy 462.5594 -52.178458) (xy 462.5594 -51.797458) (xy 463.0674 -51.797458)
				)
			)
		)
		(zone
			(layer "B.Cu")
			(hatch none 0.5)
			(connect_pads
				(clearance 0)
			)
			(min_thickness 0.25)
			(keepout
				(tracks not_allowed)
				(vias allowed)
				(pads allowed)
				(copperpour not_allowed)
				(footprints allowed)
			)
			(placement
				(enabled no)
				(sheetname "")
			)
			(fill
				(thermal_gap 0.5)
				(thermal_bridge_width 0.5)
				(island_removal_mode 0)
			)
			(polygon
				(pts
					(xy 463.0674 -51.797458) (xy 462.5594 -51.797458) (xy 462.5594 -52.178458) (xy 463.0674 -52.178458)
				)
			)
		)
	)
	(footprint ""
		(layer "B.Cu")
		(at 413.2326 -37.5412)
		(property "Reference" "C25W25"
			(at 0.8382 -0.67818 0)
			(unlocked yes)
			(layer "B.SilkS")
			(effects
				(font
					(size 0.4064 0.254)
					(thickness 0.1524)
				)
				(justify left mirror)
			)
		)
		(property "Value" ""
			(at 0 0 0)
			(layer "B.Fab")
			(effects
				(font
					(size 1.27 1.27)
				)
				(justify mirror)
			)
		)
		(duplicate_pad_numbers_are_jumpers no)
		(fp_poly
			(pts
				(xy -0.3048 -0.1016) (xy -0.3048 0.9906) (xy 0.3048 0.9906) (xy 0.3048 -0.1016)
			)
			(stroke
				(width 0)
				(type default)
			)
			(fill no)
			(layer "B.CrtYd")
		)
		(fp_line
			(start -0.3048 -0.1016)
			(end 0.3048 -0.1016)
			(stroke
				(width 0.1)
				(type default)
			)
			(layer "B.Fab")
		)
		(fp_line
			(start -0.3048 0.9906)
			(end -0.3048 -0.1016)
			(stroke
				(width 0.1)
				(type default)
			)
			(layer "B.Fab")
		)
		(fp_line
			(start 0.3048 -0.1016)
			(end 0.3048 0.9906)
			(stroke
				(width 0.1)
				(type default)
			)
			(layer "B.Fab")
		)
		(fp_line
			(start 0.3048 0.9906)
			(end -0.3048 0.9906)
			(stroke
				(width 0.1)
				(type default)
			)
			(layer "B.Fab")
		)
		(pad "1" smd rect
			(at 0 0 180)
			(size 0.508 0.508)
			(layers "B.Cu" "B.Mask" "B.Paste")
			(net "P1V15_AUX_BMC")
		)
		(pad "2" smd rect
			(at 0 0.889 180)
			(size 0.508 0.508)
			(layers "B.Cu" "B.Mask" "B.Paste")
			(net "GND")
		)
		(zone
			(layer "B.Cu")
			(hatch none 0.5)
			(connect_pads
				(clearance 0)
			)
			(min_thickness 0.25)
			(keepout
				(tracks allowed)
				(vias not_allowed)
				(pads allowed)
				(copperpour not_allowed)
				(footprints allowed)
			)
			(placement
				(enabled no)
				(sheetname "")
			)
			(fill
				(thermal_gap 0.5)
				(thermal_bridge_width 0.5)
				(island_removal_mode 0)
			)
			(polygon
				(pts
					(xy 413.4866 -37.2872) (xy 412.9786 -37.2872) (xy 412.9786 -36.9062) (xy 413.4866 -36.9062)
				)
			)
		)
		(zone
			(layer "B.Cu")
			(hatch none 0.5)
			(connect_pads
				(clearance 0)
			)
			(min_thickness 0.25)
			(keepout
				(tracks not_allowed)
				(vias allowed)
				(pads allowed)
				(copperpour not_allowed)
				(footprints allowed)
			)
			(placement
				(enabled no)
				(sheetname "")
			)
			(fill
				(thermal_gap 0.5)
				(thermal_bridge_width 0.5)
				(island_removal_mode 0)
			)
			(polygon
				(pts
					(xy 413.4866 -36.9062) (xy 412.9786 -36.9062) (xy 412.9786 -37.2872) (xy 413.4866 -37.2872)
				)
			)
		)
	)
	(footprint ""
		(layer "B.Cu")
		(at 320.194432 -8.128 90)
		(property "Reference" "C4U1"
			(at 0 0 90)
			(layer "B.SilkS")
			(hide yes)
			(effects
				(font
					(size 1.27 1.27)
				)
				(justify mirror)
			)
		)
		(property "Value" ""
			(at 0 0 90)
			(layer "B.Fab")
			(effects
				(font
					(size 1.27 1.27)
				)
				(justify mirror)
			)
		)
		(duplicate_pad_numbers_are_jumpers no)
		(fp_poly
			(pts
				(xy 0.4953 -0.2032) (xy -0.4953 -0.2032) (xy -0.4953 1.6002) (xy 0.4953 1.6002)
			)
			(stroke
				(width 0)
				(type default)
			)
			(fill no)
			(layer "B.CrtYd")
		)
		(fp_line
			(start 0.4953 -0.2032)
			(end -0.4953 -0.2032)
			(stroke
				(width 0.1)
				(type default)
			)
			(layer "B.Fab")
		)
		(fp_line
			(start -0.4953 -0.2032)
			(end -0.4953 1.6002)
			(stroke
				(width 0.1)
				(type default)
			)
			(layer "B.Fab")
		)
		(fp_line
			(start 0.4953 1.6002)
			(end 0.4953 -0.2032)
			(stroke
				(width 0.1)
				(type default)
			)
			(layer "B.Fab")
		)
		(fp_line
			(start -0.4953 1.6002)
			(end 0.4953 1.6002)
			(stroke
				(width 0.1)
				(type default)
			)
			(layer "B.Fab")
		)
		(pad "1" smd rect
			(at 0 0 270)
			(size 0.762 0.889)
			(layers "B.Cu" "B.Mask" "B.Paste")
			(net "PVPP_ABC")
		)
		(pad "2" smd rect
			(at 0 1.397 270)
			(size 0.762 0.889)
			(layers "B.Cu" "B.Mask" "B.Paste")
			(net "GND")
		)
		(zone
			(layer "B.Cu")
			(hatch none 0.5)
			(connect_pads
				(clearance 0)
			)
			(min_thickness 0.25)
			(keepout
				(tracks not_allowed)
				(vias allowed)
				(pads allowed)
				(copperpour not_allowed)
				(footprints allowed)
			)
			(placement
				(enabled no)
				(sheetname "")
			)
			(fill
				(thermal_gap 0.5)
				(thermal_bridge_width 0.5)
				(island_removal_mode 0)
			)
			(polygon
				(pts
					(xy 320.638932 -8.509) (xy 320.638932 -7.747) (xy 321.146932 -7.747) (xy 321.146932 -8.509)
				)
			)
		)
	)
)
